(kicad_pcb
	(version 20260206)
	(generator "pcbnew")
	(generator_version "10.0")
	(general
		(thickness 1.6)
		(legacy_teardrops no)
	)
	(paper "A4")
	(title_block
		(title "panther-plus-userver — 13130-1b_20150205.brd")
		(comment 1 "Honey Badger (Wiwynn) / footprints 799-806 of 1509")
	)
	(layers
		(0 "F.Cu" signal "TOP")
		(4 "In1.Cu" signal "L2")
		(6 "In2.Cu" signal "L3")
		(8 "In3.Cu" signal "L4")
		(10 "In4.Cu" signal "L5")
		(12 "In5.Cu" signal "L6")
		(14 "In6.Cu" signal "L7")
		(16 "In7.Cu" signal "L8")
		(18 "In8.Cu" signal "L9")
		(20 "In9.Cu" signal "L10")
		(22 "In10.Cu" signal "L11")
		(2 "B.Cu" signal "BOTTOM")
		(9 "F.Adhes" user "F.Adhesive")
		(11 "B.Adhes" user "B.Adhesive")
		(13 "F.Paste" user "Package Geometry/Pastemask Top")
		(15 "B.Paste" user "Package Geometry/Pastemask Bottom")
		(5 "F.SilkS" user "Ref Des/Silkscreen Top")
		(7 "B.SilkS" user "Ref Des/Silkscreen Bottom")
		(1 "F.Mask" user "Board Geometry/Soldermask Top")
		(3 "B.Mask" user "Board Geometry/Soldermask Bottom")
		(17 "Dwgs.User" user "User.Drawings")
		(19 "Cmts.User" user "User.Comments")
		(21 "Eco1.User" user "User.Eco1")
		(23 "Eco2.User" user "User.Eco2")
		(25 "Edge.Cuts" user "Board Geometry/Outline")
		(27 "Margin" user)
		(31 "F.CrtYd" user "Package Geometry/Place Bound Top")
		(29 "B.CrtYd" user "Package Geometry/Place Bound Bottom")
		(35 "F.Fab" user "Ref Des/Assembly Top")
		(33 "B.Fab" user "Ref Des/Assembly Bottom")
	)
	(footprint ""
		(layer "F.Cu")
		(at 132.588 -54.737 -90)
		(property "Reference" "PC66"
			(at 0 0 270)
			(layer "F.SilkS")
			(hide yes)
			(effects
				(font
					(size 1.27 1.27)
				)
			)
		)
		(property "Value" "SCD1U16V2KX-3GP"
			(at 1.1811 -2.7051 270)
			(unlocked yes)
			(layer "F.Fab")
			(hide yes)
			(effects
				(font
					(size 1.016 1.016)
					(thickness 0.1524)
				)
			)
		)
		(property "Device Type" "C402H22"
			(at 1.1811 -4.2291 270)
			(unlocked yes)
			(layer "F.Fab")
			(hide yes)
			(effects
				(font
					(size 1.016 1.016)
					(thickness 0.1524)
				)
			)
		)
		(duplicate_pad_numbers_are_jumpers no)
		(fp_rect
			(start -0.381 0.7366)
			(end 0.381 -0.7366)
			(stroke
				(width 0)
				(type default)
			)
			(fill no)
			(layer "F.CrtYd")
		)
		(fp_rect
			(start -0.381 0.7366)
			(end 0.381 -0.7366)
			(stroke
				(width 0)
				(type default)
			)
			(fill no)
			(layer "F.Fab")
		)
		(pad "1" smd custom
			(at 0 -0.4572 270)
			(size 0.1143 0.1143)
			(layers "F.Cu" "F.Mask" "F.Paste")
			(net "PV_VTT_DDR_SNS")
			(options
				(clearance outline)
				(anchor circle)
			)
			(primitives
				(gr_poly
					(pts
						(arc
							(start -0.254 -0.1778)
							(mid -0.239121 -0.213721)
							(end -0.2032 -0.2286)
						)
						(arc
							(start 0.2032 -0.2286)
							(mid 0.239121 -0.213721)
							(end 0.254 -0.1778)
						)
						(arc
							(start 0.254 0.1778)
							(mid 0.239121 0.213721)
							(end 0.2032 0.2286)
						)
						(arc
							(start -0.2032 0.2286)
							(mid -0.239121 0.213721)
							(end -0.254 0.1778)
						)
					)
					(width 0)
					(fill yes)
				)
			)
		)
		(pad "2" smd custom
			(at 0 0.4572 270)
			(size 0.1143 0.1143)
			(layers "F.Cu" "F.Mask" "F.Paste")
			(net "GND")
			(options
				(clearance outline)
				(anchor circle)
			)
			(primitives
				(gr_poly
					(pts
						(arc
							(start -0.254 -0.1778)
							(mid -0.239121 -0.213721)
							(end -0.2032 -0.2286)
						)
						(arc
							(start 0.2032 -0.2286)
							(mid 0.239121 -0.213721)
							(end 0.254 -0.1778)
						)
						(arc
							(start 0.254 0.1778)
							(mid 0.239121 0.213721)
							(end 0.2032 0.2286)
						)
						(arc
							(start -0.2032 0.2286)
							(mid -0.239121 0.213721)
							(end -0.254 0.1778)
						)
					)
					(width 0)
					(fill yes)
				)
			)
		)
	)
	(footprint ""
		(layer "F.Cu")
		(at 50.2158 -12.7)
		(property "Reference" "C313"
			(at 0 0 0)
			(layer "F.SilkS")
			(hide yes)
			(effects
				(font
					(size 1.27 1.27)
				)
			)
		)
		(property "Value" "SCD047U25V2KX-GP"
			(at 1.8923 -1.2065 0)
			(unlocked yes)
			(layer "F.Fab")
			(hide yes)
			(effects
				(font
					(size 1.016 1.016)
					(thickness 0.1524)
				)
			)
		)
		(property "Device Type" "C402H22"
			(at 1.8923 -2.7305 0)
			(unlocked yes)
			(layer "F.Fab")
			(hide yes)
			(effects
				(font
					(size 1.016 1.016)
					(thickness 0.1524)
				)
			)
		)
		(duplicate_pad_numbers_are_jumpers no)
		(fp_rect
			(start -0.381 0.7366)
			(end 0.381 -0.7366)
			(stroke
				(width 0)
				(type default)
			)
			(fill no)
			(layer "F.CrtYd")
		)
		(fp_rect
			(start -0.381 0.7366)
			(end 0.381 -0.7366)
			(stroke
				(width 0)
				(type default)
			)
			(fill no)
			(layer "F.Fab")
		)
		(pad "1" smd custom
			(at 0 -0.4572)
			(size 0.1143 0.1143)
			(layers "F.Cu" "F.Mask" "F.Paste")
			(net "CPU_GBE_TX_DP0")
			(options
				(clearance outline)
				(anchor circle)
			)
			(primitives
				(gr_poly
					(pts
						(arc
							(start -0.254 -0.1778)
							(mid -0.239121 -0.213721)
							(end -0.2032 -0.2286)
						)
						(arc
							(start 0.2032 -0.2286)
							(mid 0.239121 -0.213721)
							(end 0.254 -0.1778)
						)
						(arc
							(start 0.254 0.1778)
							(mid 0.239121 0.213721)
							(end 0.2032 0.2286)
						)
						(arc
							(start -0.2032 0.2286)
							(mid -0.239121 0.213721)
							(end -0.254 0.1778)
						)
					)
					(width 0)
					(fill yes)
				)
			)
		)
		(pad "2" smd custom
			(at 0 0.4572)
			(size 0.1143 0.1143)
			(layers "F.Cu" "F.Mask" "F.Paste")
			(net "CPU_GBE_TX_C_DP0")
			(options
				(clearance outline)
				(anchor circle)
			)
			(primitives
				(gr_poly
					(pts
						(arc
							(start -0.254 -0.1778)
							(mid -0.239121 -0.213721)
							(end -0.2032 -0.2286)
						)
						(arc
							(start 0.2032 -0.2286)
							(mid 0.239121 -0.213721)
							(end 0.254 -0.1778)
						)
						(arc
							(start 0.254 0.1778)
							(mid 0.239121 0.213721)
							(end 0.2032 0.2286)
						)
						(arc
							(start -0.2032 0.2286)
							(mid -0.239121 0.213721)
							(end -0.254 0.1778)
						)
					)
					(width 0)
					(fill yes)
				)
			)
		)
	)
	(footprint ""
		(layer "F.Cu")
		(at 128.143 -36.83 -90)
		(property "Reference" "R30"
			(at 0 0 270)
			(layer "F.SilkS")
			(hide yes)
			(effects
				(font
					(size 1.27 1.27)
				)
			)
		)
		(property "Value" "33R2F-3-GP"
			(at 0.064008 -3.993896 270)
			(unlocked yes)
			(layer "F.Fab")
			(hide yes)
			(effects
				(font
					(size 1.016 1.016)
					(thickness 0.1524)
				)
			)
		)
		(property "Device Type" "R402H16"
			(at 0.064008 -5.517896 270)
			(unlocked yes)
			(layer "F.Fab")
			(hide yes)
			(effects
				(font
					(size 1.016 1.016)
					(thickness 0.1524)
				)
			)
		)
		(duplicate_pad_numbers_are_jumpers no)
		(fp_rect
			(start -0.381 0.8382)
			(end 0.381 -0.8382)
			(stroke
				(width 0)
				(type default)
			)
			(fill no)
			(layer "F.CrtYd")
		)
		(fp_rect
			(start -0.381 0.8382)
			(end 0.381 -0.8382)
			(stroke
				(width 0)
				(type default)
			)
			(fill no)
			(layer "F.Fab")
		)
		(pad "1" smd custom
			(at 0 -0.4318 270)
			(size 0.127 0.127)
			(layers "F.Cu" "F.Mask" "F.Paste")
			(net "LPC_AD_2")
			(options
				(clearance outline)
				(anchor circle)
			)
			(primitives
				(gr_poly
					(pts
						(arc
							(start -0.2032 -0.2794)
							(mid -0.239121 -0.264521)
							(end -0.254 -0.2286)
						)
						(arc
							(start -0.254 0.2286)
							(mid -0.239121 0.264521)
							(end -0.2032 0.2794)
						)
						(arc
							(start 0.2032 0.2794)
							(mid 0.239121 0.264521)
							(end 0.254 0.2286)
						)
						(arc
							(start 0.254 -0.2286)
							(mid 0.239121 -0.264521)
							(end 0.2032 -0.2794)
						)
					)
					(width 0)
					(fill yes)
				)
			)
		)
		(pad "2" smd custom
			(at 0 0.4318 270)
			(size 0.127 0.127)
			(layers "F.Cu" "F.Mask" "F.Paste")
			(net "LPC_CPU_LAD2")
			(options
				(clearance outline)
				(anchor circle)
			)
			(primitives
				(gr_poly
					(pts
						(arc
							(start -0.2032 -0.2794)
							(mid -0.239121 -0.264521)
							(end -0.254 -0.2286)
						)
						(arc
							(start -0.254 0.2286)
							(mid -0.239121 0.264521)
							(end -0.2032 0.2794)
						)
						(arc
							(start 0.2032 0.2794)
							(mid 0.239121 0.264521)
							(end 0.254 0.2286)
						)
						(arc
							(start 0.254 -0.2286)
							(mid 0.239121 -0.264521)
							(end 0.2032 -0.2794)
						)
					)
					(width 0)
					(fill yes)
				)
			)
		)
	)
	(footprint ""
		(layer "F.Cu")
		(at 141.2748 -56.0578 -90)
		(property "Reference" "PR72"
			(at 0 0 270)
			(layer "F.SilkS")
			(hide yes)
			(effects
				(font
					(size 1.27 1.27)
				)
			)
		)
		(property "Value" "0R2J-2-GP"
			(at 0.064008 -3.993896 270)
			(unlocked yes)
			(layer "F.Fab")
			(hide yes)
			(effects
				(font
					(size 1.016 1.016)
					(thickness 0.1524)
				)
			)
		)
		(property "Device Type" "R402H16"
			(at 0.064008 -5.517896 270)
			(unlocked yes)
			(layer "F.Fab")
			(hide yes)
			(effects
				(font
					(size 1.016 1.016)
					(thickness 0.1524)
				)
			)
		)
		(duplicate_pad_numbers_are_jumpers no)
		(fp_rect
			(start -0.381 0.8382)
			(end 0.381 -0.8382)
			(stroke
				(width 0)
				(type default)
			)
			(fill no)
			(layer "F.CrtYd")
		)
		(fp_rect
			(start -0.381 0.8382)
			(end 0.381 -0.8382)
			(stroke
				(width 0)
				(type default)
			)
			(fill no)
			(layer "F.Fab")
		)
		(pad "1" smd custom
			(at 0 -0.4318 270)
			(size 0.127 0.127)
			(layers "F.Cu" "F.Mask" "F.Paste")
			(net "PVTT_DDR_EN")
			(options
				(clearance outline)
				(anchor circle)
			)
			(primitives
				(gr_poly
					(pts
						(arc
							(start -0.2032 -0.2794)
							(mid -0.239121 -0.264521)
							(end -0.254 -0.2286)
						)
						(arc
							(start -0.254 0.2286)
							(mid -0.239121 0.264521)
							(end -0.2032 0.2794)
						)
						(arc
							(start 0.2032 0.2794)
							(mid 0.239121 0.264521)
							(end 0.254 0.2286)
						)
						(arc
							(start 0.254 -0.2286)
							(mid 0.239121 -0.264521)
							(end 0.2032 -0.2794)
						)
					)
					(width 0)
					(fill yes)
				)
			)
		)
		(pad "2" smd custom
			(at 0 0.4318 270)
			(size 0.127 0.127)
			(layers "F.Cu" "F.Mask" "F.Paste")
			(net "PV_VTT_DDR_EN")
			(options
				(clearance outline)
				(anchor circle)
			)
			(primitives
				(gr_poly
					(pts
						(arc
							(start -0.2032 -0.2794)
							(mid -0.239121 -0.264521)
							(end -0.254 -0.2286)
						)
						(arc
							(start -0.254 0.2286)
							(mid -0.239121 0.264521)
							(end -0.2032 0.2794)
						)
						(arc
							(start 0.2032 0.2794)
							(mid 0.239121 0.264521)
							(end 0.254 0.2286)
						)
						(arc
							(start 0.254 -0.2286)
							(mid 0.239121 -0.264521)
							(end 0.2032 -0.2794)
						)
					)
					(width 0)
					(fill yes)
				)
			)
		)
	)
	(footprint ""
		(layer "F.Cu")
		(at 68.072 -50.292 -90)
		(property "Reference" "R460"
			(at 0 0 270)
			(layer "F.SilkS")
			(hide yes)
			(effects
				(font
					(size 1.27 1.27)
				)
			)
		)
		(property "Value" "0R2J-2-GP"
			(at 1.7907 -1.1176 270)
			(unlocked yes)
			(layer "F.Fab")
			(hide yes)
			(effects
				(font
					(size 1.016 1.016)
					(thickness 0.1524)
				)
			)
		)
		(property "Device Type" "R402H16"
			(at 1.7907 -2.6416 270)
			(unlocked yes)
			(layer "F.Fab")
			(hide yes)
			(effects
				(font
					(size 1.016 1.016)
					(thickness 0.1524)
				)
			)
		)
		(duplicate_pad_numbers_are_jumpers no)
		(fp_rect
			(start -0.381 0.8382)
			(end 0.381 -0.8382)
			(stroke
				(width 0)
				(type default)
			)
			(fill no)
			(layer "F.CrtYd")
		)
		(fp_rect
			(start -0.381 0.8382)
			(end 0.381 -0.8382)
			(stroke
				(width 0)
				(type default)
			)
			(fill no)
			(layer "F.Fab")
		)
		(pad "1" smd custom
			(at 0 -0.4318 270)
			(size 0.127 0.127)
			(layers "F.Cu" "F.Mask" "F.Paste")
			(net "SMBUS_PECI_SW_EN")
			(options
				(clearance outline)
				(anchor circle)
			)
			(primitives
				(gr_poly
					(pts
						(arc
							(start -0.2032 -0.2794)
							(mid -0.239121 -0.264521)
							(end -0.254 -0.2286)
						)
						(arc
							(start -0.254 0.2286)
							(mid -0.239121 0.264521)
							(end -0.2032 0.2794)
						)
						(arc
							(start 0.2032 0.2794)
							(mid 0.239121 0.264521)
							(end 0.254 0.2286)
						)
						(arc
							(start 0.254 -0.2286)
							(mid 0.239121 -0.264521)
							(end 0.2032 -0.2794)
						)
					)
					(width 0)
					(fill yes)
				)
			)
		)
		(pad "2" smd custom
			(at 0 0.4318 270)
			(size 0.127 0.127)
			(layers "F.Cu" "F.Mask" "F.Paste")
			(net "SMBUS_SW_INV_D")
			(options
				(clearance outline)
				(anchor circle)
			)
			(primitives
				(gr_poly
					(pts
						(arc
							(start -0.2032 -0.2794)
							(mid -0.239121 -0.264521)
							(end -0.254 -0.2286)
						)
						(arc
							(start -0.254 0.2286)
							(mid -0.239121 0.264521)
							(end -0.2032 0.2794)
						)
						(arc
							(start 0.2032 0.2794)
							(mid 0.239121 0.264521)
							(end 0.254 0.2286)
						)
						(arc
							(start 0.254 -0.2286)
							(mid 0.239121 -0.264521)
							(end 0.2032 -0.2794)
						)
					)
					(width 0)
					(fill yes)
				)
			)
		)
	)
	(footprint ""
		(layer "F.Cu")
		(at 12.954 -29.464 -90)
		(property "Reference" "PC76"
			(at 0 0 270)
			(layer "F.SilkS")
			(hide yes)
			(effects
				(font
					(size 1.27 1.27)
				)
			)
		)
		(property "Value" "SC470P50V2KX-3GP"
			(at 1.8923 -1.2065 270)
			(unlocked yes)
			(layer "F.Fab")
			(hide yes)
			(effects
				(font
					(size 1.016 1.016)
					(thickness 0.1524)
				)
			)
		)
		(property "Device Type" "C402H22"
			(at 1.8923 -2.7305 270)
			(unlocked yes)
			(layer "F.Fab")
			(hide yes)
			(effects
				(font
					(size 1.016 1.016)
					(thickness 0.1524)
				)
			)
		)
		(duplicate_pad_numbers_are_jumpers no)
		(fp_rect
			(start -0.381 0.7366)
			(end 0.381 -0.7366)
			(stroke
				(width 0)
				(type default)
			)
			(fill no)
			(layer "F.CrtYd")
		)
		(fp_rect
			(start -0.381 0.7366)
			(end 0.381 -0.7366)
			(stroke
				(width 0)
				(type default)
			)
			(fill no)
			(layer "F.Fab")
		)
		(pad "1" smd custom
			(at 0 -0.4572 270)
			(size 0.1143 0.1143)
			(layers "F.Cu" "F.Mask" "F.Paste")
			(net "P1V0_SNB")
			(options
				(clearance outline)
				(anchor circle)
			)
			(primitives
				(gr_poly
					(pts
						(arc
							(start -0.254 -0.1778)
							(mid -0.239121 -0.213721)
							(end -0.2032 -0.2286)
						)
						(arc
							(start 0.2032 -0.2286)
							(mid 0.239121 -0.213721)
							(end 0.254 -0.1778)
						)
						(arc
							(start 0.254 0.1778)
							(mid 0.239121 0.213721)
							(end 0.2032 0.2286)
						)
						(arc
							(start -0.2032 0.2286)
							(mid -0.239121 0.213721)
							(end -0.254 0.1778)
						)
					)
					(width 0)
					(fill yes)
				)
			)
		)
		(pad "2" smd custom
			(at 0 0.4572 270)
			(size 0.1143 0.1143)
			(layers "F.Cu" "F.Mask" "F.Paste")
			(net "GND")
			(options
				(clearance outline)
				(anchor circle)
			)
			(primitives
				(gr_poly
					(pts
						(arc
							(start -0.254 -0.1778)
							(mid -0.239121 -0.213721)
							(end -0.2032 -0.2286)
						)
						(arc
							(start 0.2032 -0.2286)
							(mid 0.239121 -0.213721)
							(end 0.254 -0.1778)
						)
						(arc
							(start 0.254 0.1778)
							(mid 0.239121 0.213721)
							(end 0.2032 0.2286)
						)
						(arc
							(start -0.2032 0.2286)
							(mid -0.239121 0.213721)
							(end -0.254 0.1778)
						)
					)
					(width 0)
					(fill yes)
				)
			)
		)
	)
	(footprint ""
		(layer "F.Cu")
		(at 29.2608 -55.3212 -90)
		(property "Reference" "PR50"
			(at 0 0 270)
			(layer "F.SilkS")
			(hide yes)
			(effects
				(font
					(size 1.27 1.27)
				)
			)
		)
		(property "Value" "10KR2F-2-GP"
			(at 1.7907 -1.1176 270)
			(unlocked yes)
			(layer "F.Fab")
			(hide yes)
			(effects
				(font
					(size 1.016 1.016)
					(thickness 0.1524)
				)
			)
		)
		(property "Device Type" "R402H16"
			(at 1.7907 -2.6416 270)
			(unlocked yes)
			(layer "F.Fab")
			(hide yes)
			(effects
				(font
					(size 1.016 1.016)
					(thickness 0.1524)
				)
			)
		)
		(duplicate_pad_numbers_are_jumpers no)
		(fp_rect
			(start -0.381 0.8382)
			(end 0.381 -0.8382)
			(stroke
				(width 0)
				(type default)
			)
			(fill no)
			(layer "F.CrtYd")
		)
		(fp_rect
			(start -0.381 0.8382)
			(end 0.381 -0.8382)
			(stroke
				(width 0)
				(type default)
			)
			(fill no)
			(layer "F.Fab")
		)
		(pad "1" smd custom
			(at 0 -0.4318 270)
			(size 0.127 0.127)
			(layers "F.Cu" "F.Mask" "F.Paste")
			(net "VR_PVCCP_PHASE")
			(options
				(clearance outline)
				(anchor circle)
			)
			(primitives
				(gr_poly
					(pts
						(arc
							(start -0.2032 -0.2794)
							(mid -0.239121 -0.264521)
							(end -0.254 -0.2286)
						)
						(arc
							(start -0.254 0.2286)
							(mid -0.239121 0.264521)
							(end -0.2032 0.2794)
						)
						(arc
							(start 0.2032 0.2794)
							(mid 0.239121 0.264521)
							(end 0.254 0.2286)
						)
						(arc
							(start 0.254 -0.2286)
							(mid 0.239121 -0.264521)
							(end 0.2032 -0.2794)
						)
					)
					(width 0)
					(fill yes)
				)
			)
		)
		(pad "2" smd custom
			(at 0 0.4318 270)
			(size 0.127 0.127)
			(layers "F.Cu" "F.Mask" "F.Paste")
			(net "VR_PVCCP_GH_R")
			(options
				(clearance outline)
				(anchor circle)
			)
			(primitives
				(gr_poly
					(pts
						(arc
							(start -0.2032 -0.2794)
							(mid -0.239121 -0.264521)
							(end -0.254 -0.2286)
						)
						(arc
							(start -0.254 0.2286)
							(mid -0.239121 0.264521)
							(end -0.2032 0.2794)
						)
						(arc
							(start 0.2032 0.2794)
							(mid 0.239121 0.264521)
							(end 0.254 0.2286)
						)
						(arc
							(start 0.254 -0.2286)
							(mid 0.239121 -0.264521)
							(end 0.2032 -0.2794)
						)
					)
					(width 0)
					(fill yes)
				)
			)
		)
	)
	(footprint ""
		(layer "F.Cu")
		(at 56.515 -42.037 180)
		(property "Reference" "U11"
			(at 0 0 180)
			(layer "F.SilkS")
			(hide yes)
			(effects
				(font
					(size 1.27 1.27)
				)
			)
		)
		(property "Value" "2N7002DW-7F-GP"
			(at -2.5654 1.1049 180)
			(unlocked yes)
			(layer "F.Fab")
			(hide yes)
			(effects
				(font
					(size 1.016 1.016)
					(thickness 0.1524)
				)
			)
		)
		(property "Device Type" "SOT-363H44"
			(at -2.5654 -0.4191 180)
			(unlocked yes)
			(layer "F.Fab")
			(hide yes)
			(effects
				(font
					(size 1.016 1.016)
					(thickness 0.1524)
				)
			)
		)
		(duplicate_pad_numbers_are_jumpers no)
		(fp_poly
			(pts
				(xy -0.6477 1.4351) (xy -0.9525 1.7399) (xy -0.3556 1.7399) (xy -0.3429 1.7399) (xy -0.3556 1.7272)
			)
			(stroke
				(width 0)
				(type default)
			)
			(fill yes)
			(layer "F.SilkS")
		)
		(fp_poly
			(pts
				(xy 1.2573 0.8763) (xy 1.2573 -0.8763) (xy 0.9525 -0.8763) (xy 0.9525 -1.4351) (xy -0.9525 -1.4351)
				(xy -0.9525 -0.8763) (xy -1.2573 -0.8763) (xy -1.2573 0.8763) (xy -0.9525 0.8763) (xy -0.9525 1.4351)
				(xy 0.9525 1.4351) (xy 0.9525 0.8763)
			)
			(stroke
				(width 0)
				(type default)
			)
			(fill no)
			(layer "F.CrtYd")
		)
		(fp_poly
			(pts
				(xy 1.2573 0.8763) (xy 1.2573 -0.8763) (xy 0.9525 -0.8763) (xy 0.9525 -1.4351) (xy -0.9525 -1.4351)
				(xy -0.9525 -0.8763) (xy -1.2573 -0.8763) (xy -1.2573 0.8763) (xy -0.9525 0.8763) (xy -0.9525 1.4351)
				(xy 0.9525 1.4351) (xy 0.9525 0.8763)
			)
			(stroke
				(width 0)
				(type default)
			)
			(fill no)
			(layer "F.Fab")
		)
		(pad "1" smd rect
			(at -0.65024 0.8255 180)
			(size 0.3556 0.9652)
			(layers "F.Cu" "F.Mask" "F.Paste")
			(net "GND")
		)
		(pad "2" smd rect
			(at 0 0.8255 180)
			(size 0.3556 0.9652)
			(layers "F.Cu" "F.Mask" "F.Paste")
			(net "SW_P3V3_EN_G2")
		)
		(pad "3" smd rect
			(at 0.65024 0.8255 180)
			(size 0.3556 0.9652)
			(layers "F.Cu" "F.Mask" "F.Paste")
			(net "SW_P3V3_EN_LV_D")
		)
		(pad "4" smd rect
			(at 0.65024 -0.8255 180)
			(size 0.3556 0.9652)
			(layers "F.Cu" "F.Mask" "F.Paste")
			(net "GND")
		)
		(pad "5" smd rect
			(at 0 -0.8255 180)
			(size 0.3556 0.9652)
			(layers "F.Cu" "F.Mask" "F.Paste")
			(net "SW_P3V3_LV_G5")
		)
		(pad "6" smd rect
			(at -0.65024 -0.8255 180)
			(size 0.3556 0.9652)
			(layers "F.Cu" "F.Mask" "F.Paste")
			(net "SW_P3V3_LV_G5")
		)
	)
)
